# S9S_MB_2U (Grand Teton) — schematic netlist excerpt (pin names and nets, part order shuffled) for the footprints in the layout excerpt that follows; sources: Cadence DE-HDL packaged netlist, KiCad conversion of 03242023_DA0F0TMBIJ0_F0T_Motherboard_J_brd_V01_OCP.brd

R3228  Q_RES  200 1% CHIP  pkg 0402LF  page 159 : A = SMB_OCP_V3_2_3V3AUX_BUF_R_SCL ; B = SMB_OCP_V3_2_3V3AUX_BUF_SCL
R3074  Q_RES  130 1% CHIP  pkg 0402LF  page 252 : A = LED_RST_RSMRST_PLD_R_N ; B = P3V3_AUX

(kicad_pcb
	(version 20260206)
	(generator "pcbnew")
	(generator_version "10.0")
	(general
		(thickness 1.6)
		(legacy_teardrops no)
	)
	(paper "A4")
	(title_block
		(title "03242023_DA0F0TMBIJ0_F0T_Motherboard_J_brd_V01_OCP.brd")
		(comment 1 "Grand Teton / footprints 217-218 of 6105")
	)
	(layers
		(0 "F.Cu" signal "TOP")
		(4 "In1.Cu" signal "GND")
		(6 "In2.Cu" signal "IN1")
		(8 "In3.Cu" signal "GND1")
		(10 "In4.Cu" signal "IN2")
		(12 "In5.Cu" signal "GND2")
		(14 "In6.Cu" signal "IN3")
		(16 "In7.Cu" signal "GND3")
		(18 "In8.Cu" signal "VCC")
		(20 "In9.Cu" signal "VCC1")
		(22 "In10.Cu" signal "GND4")
		(24 "In11.Cu" signal "IN4")
		(26 "In12.Cu" signal "GND5")
		(28 "In13.Cu" signal "IN5")
		(30 "In14.Cu" signal "GND6")
		(32 "In15.Cu" signal "IN6")
		(34 "In16.Cu" signal "GND7")
		(2 "B.Cu" signal "BOTTOM")
		(9 "F.Adhes" user "F.Adhesive")
		(11 "B.Adhes" user "B.Adhesive")
		(13 "F.Paste" user "Package Geometry/Pastemask Top")
		(15 "B.Paste" user "Package Geometry/Pastemask Bottom")
		(5 "F.SilkS" user "Ref Des/Silkscreen Top")
		(7 "B.SilkS" user "Ref Des/Silkscreen Bottom")
		(1 "F.Mask" user "Board Geometry/Soldermask Top")
		(3 "B.Mask" user "Board Geometry/Soldermask Bottom")
		(17 "Dwgs.User" user "User.Drawings")
		(19 "Cmts.User" user "User.Comments")
		(21 "Eco1.User" user "User.Eco1")
		(23 "Eco2.User" user "User.Eco2")
		(25 "Edge.Cuts" user "Board Geometry/Outline")
		(27 "Margin" user)
		(31 "F.CrtYd" user "Package Geometry/Place Bound Top")
		(29 "B.CrtYd" user "Package Geometry/Place Bound Bottom")
		(35 "F.Fab" user "Ref Des/Assembly Top")
		(33 "B.Fab" user "Ref Des/Assembly Bottom")
	)
	(footprint ""
		(layer "F.Cu")
		(at 95.94596 -31.575248)
		(property "Reference" "R3228"
			(at 0 0 0)
			(layer "F.SilkS")
			(hide yes)
			(effects
				(font
					(size 1.27 1.27)
				)
			)
		)
		(property "Value" ""
			(at 0 0 0)
			(layer "F.Fab")
			(effects
				(font
					(size 1.27 1.27)
				)
			)
		)
		(duplicate_pad_numbers_are_jumpers no)
		(fp_line
			(start -0.7874 -0.4064)
			(end 0.7874 -0.4064)
			(stroke
				(width 0.1524)
				(type default)
			)
			(layer "F.SilkS")
		)
		(fp_line
			(start -0.7874 0.4064)
			(end -0.7874 -0.4064)
			(stroke
				(width 0.1524)
				(type default)
			)
			(layer "F.SilkS")
		)
		(fp_line
			(start 0.7874 -0.4064)
			(end 0.7874 0.4064)
			(stroke
				(width 0.1524)
				(type default)
			)
			(layer "F.SilkS")
		)
		(fp_line
			(start 0.7874 0.4064)
			(end -0.7874 0.4064)
			(stroke
				(width 0.1524)
				(type default)
			)
			(layer "F.SilkS")
		)
		(fp_line
			(start -0.67945 -0.305054)
			(end -0.12065 -0.305054)
			(stroke
				(width 0.1)
				(type default)
			)
			(layer "F.Fab")
		)
		(fp_line
			(start -0.67945 0.3048)
			(end -0.67945 -0.305054)
			(stroke
				(width 0.1)
				(type default)
			)
			(layer "F.Fab")
		)
		(fp_line
			(start -0.12065 -0.305054)
			(end -0.12065 -0.2794)
			(stroke
				(width 0.1)
				(type default)
			)
			(layer "F.Fab")
		)
		(fp_line
			(start -0.12065 -0.2794)
			(end 0.12065 -0.2794)
			(stroke
				(width 0.1)
				(type default)
			)
			(layer "F.Fab")
		)
		(fp_line
			(start -0.12065 0.2794)
			(end -0.12065 0.3048)
			(stroke
				(width 0.1)
				(type default)
			)
			(layer "F.Fab")
		)
		(fp_line
			(start -0.12065 0.3048)
			(end -0.67945 0.3048)
			(stroke
				(width 0.1)
				(type default)
			)
			(layer "F.Fab")
		)
		(fp_line
			(start 0.120396 0.2794)
			(end -0.12065 0.2794)
			(stroke
				(width 0.1)
				(type default)
			)
			(layer "F.Fab")
		)
		(fp_line
			(start 0.120396 0.3048)
			(end 0.120396 0.2794)
			(stroke
				(width 0.1)
				(type default)
			)
			(layer "F.Fab")
		)
		(fp_line
			(start 0.12065 -0.3048)
			(end 0.67945 -0.3048)
			(stroke
				(width 0.1)
				(type default)
			)
			(layer "F.Fab")
		)
		(fp_line
			(start 0.12065 -0.2794)
			(end 0.12065 -0.3048)
			(stroke
				(width 0.1)
				(type default)
			)
			(layer "F.Fab")
		)
		(fp_line
			(start 0.67945 -0.3048)
			(end 0.67945 0.3048)
			(stroke
				(width 0.1)
				(type default)
			)
			(layer "F.Fab")
		)
		(fp_line
			(start 0.67945 0.3048)
			(end 0.120396 0.3048)
			(stroke
				(width 0.1)
				(type default)
			)
			(layer "F.Fab")
		)
		(pad "1" smd circle
			(at -0.40005 0)
			(size 0 0)
			(layers "F.Cu" "F.Mask" "F.Paste")
			(net "SMB_OCP_V3_2_3V3AUX_BUF_R_SCL")
		)
		(pad "2" smd circle
			(at 0.40005 0)
			(size 0 0)
			(layers "F.Cu" "F.Mask" "F.Paste")
			(net "SMB_OCP_V3_2_3V3AUX_BUF_SCL")
		)
	)
	(footprint ""
		(layer "F.Cu")
		(at 102.67061 -74.95921 -90)
		(property "Reference" "R3074"
			(at 0 0 270)
			(layer "F.SilkS")
			(hide yes)
			(effects
				(font
					(size 1.27 1.27)
				)
			)
		)
		(property "Value" ""
			(at 0 0 270)
			(layer "F.Fab")
			(effects
				(font
					(size 1.27 1.27)
				)
			)
		)
		(duplicate_pad_numbers_are_jumpers no)
		(fp_line
			(start -0.7874 0.4064)
			(end -0.7874 -0.4064)
			(stroke
				(width 0.1524)
				(type default)
			)
			(layer "F.SilkS")
		)
		(fp_line
			(start 0.7874 0.4064)
			(end -0.7874 0.4064)
			(stroke
				(width 0.1524)
				(type default)
			)
			(layer "F.SilkS")
		)
		(fp_line
			(start -0.7874 -0.4064)
			(end 0.7874 -0.4064)
			(stroke
				(width 0.1524)
				(type default)
			)
			(layer "F.SilkS")
		)
		(fp_line
			(start 0.7874 -0.4064)
			(end 0.7874 0.4064)
			(stroke
				(width 0.1524)
				(type default)
			)
			(layer "F.SilkS")
		)
		(fp_line
			(start -0.67945 0.3048)
			(end -0.67945 -0.305054)
			(stroke
				(width 0.1)
				(type default)
			)
			(layer "F.Fab")
		)
		(fp_line
			(start -0.12065 0.3048)
			(end -0.67945 0.3048)
			(stroke
				(width 0.1)
				(type default)
			)
			(layer "F.Fab")
		)
		(fp_line
			(start 0.120396 0.3048)
			(end 0.120396 0.2794)
			(stroke
				(width 0.1)
				(type default)
			)
			(layer "F.Fab")
		)
		(fp_line
			(start 0.67945 0.3048)
			(end 0.120396 0.3048)
			(stroke
				(width 0.1)
				(type default)
			)
			(layer "F.Fab")
		)
		(fp_line
			(start -0.12065 0.2794)
			(end -0.12065 0.3048)
			(stroke
				(width 0.1)
				(type default)
			)
			(layer "F.Fab")
		)
		(fp_line
			(start 0.120396 0.2794)
			(end -0.12065 0.2794)
			(stroke
				(width 0.1)
				(type default)
			)
			(layer "F.Fab")
		)
		(fp_line
			(start -0.12065 -0.2794)
			(end 0.12065 -0.2794)
			(stroke
				(width 0.1)
				(type default)
			)
			(layer "F.Fab")
		)
		(fp_line
			(start 0.12065 -0.2794)
			(end 0.12065 -0.3048)
			(stroke
				(width 0.1)
				(type default)
			)
			(layer "F.Fab")
		)
		(fp_line
			(start 0.12065 -0.3048)
			(end 0.67945 -0.3048)
			(stroke
				(width 0.1)
				(type default)
			)
			(layer "F.Fab")
		)
		(fp_line
			(start 0.67945 -0.3048)
			(end 0.67945 0.3048)
			(stroke
				(width 0.1)
				(type default)
			)
			(layer "F.Fab")
		)
		(fp_line
			(start -0.67945 -0.305054)
			(end -0.12065 -0.305054)
			(stroke
				(width 0.1)
				(type default)
			)
			(layer "F.Fab")
		)
		(fp_line
			(start -0.12065 -0.305054)
			(end -0.12065 -0.2794)
			(stroke
				(width 0.1)
				(type default)
			)
			(layer "F.Fab")
		)
		(pad "1" smd circle
			(at -0.40005 0 270)
			(size 0 0)
			(layers "F.Cu" "F.Mask" "F.Paste")
			(net "LED_RST_RSMRST_PLD_R_N")
		)
		(pad "2" smd circle
			(at 0.40005 0 270)
			(size 0 0)
			(layers "F.Cu" "F.Mask" "F.Paste")
			(net "P3V3_AUX")
		)
	)
)
